(kicad_pcb
	(version 20260206)
	(generator "pcbnew")
	(generator_version "10.0")
	(general
		(thickness 1.6)
		(legacy_teardrops no)
	)
	(paper "A4")
	(title_block
		(title "04192023_DAF0TMB3IC0_F0TG_MB_C_brd_V02_OCP.brd")
		(comment 1 "Grand Teton / footprints 4384-4389 of 8354")
	)
	(layers
		(0 "F.Cu" signal "TOP")
		(4 "In1.Cu" signal "GND")
		(6 "In2.Cu" signal "IN1")
		(8 "In3.Cu" signal "GND1")
		(10 "In4.Cu" signal "IN2")
		(12 "In5.Cu" signal "GND2")
		(14 "In6.Cu" signal "IN3")
		(16 "In7.Cu" signal "GND3")
		(18 "In8.Cu" signal "VCC")
		(20 "In9.Cu" signal "VCC1")
		(22 "In10.Cu" signal "GND4")
		(24 "In11.Cu" signal "IN4")
		(26 "In12.Cu" signal "GND5")
		(28 "In13.Cu" signal "IN5")
		(30 "In14.Cu" signal "GND6")
		(32 "In15.Cu" signal "IN6")
		(34 "In16.Cu" signal "GND7")
		(2 "B.Cu" signal "BOTTOM")
		(9 "F.Adhes" user "F.Adhesive")
		(11 "B.Adhes" user "B.Adhesive")
		(13 "F.Paste" user "Package Geometry/Pastemask Top")
		(15 "B.Paste" user "Package Geometry/Pastemask Bottom")
		(5 "F.SilkS" user "Ref Des/Silkscreen Top")
		(7 "B.SilkS" user "Ref Des/Silkscreen Bottom")
		(1 "F.Mask" user "Board Geometry/Soldermask Top")
		(3 "B.Mask" user "Board Geometry/Soldermask Bottom")
		(17 "Dwgs.User" user "User.Drawings")
		(19 "Cmts.User" user "User.Comments")
		(21 "Eco1.User" user "User.Eco1")
		(23 "Eco2.User" user "User.Eco2")
		(25 "Edge.Cuts" user "Board Geometry/Outline")
		(27 "Margin" user)
		(31 "F.CrtYd" user "Package Geometry/Place Bound Top")
		(29 "B.CrtYd" user "Package Geometry/Place Bound Bottom")
		(35 "F.Fab" user "Ref Des/Assembly Top")
		(33 "B.Fab" user "Ref Des/Assembly Bottom")
	)
	(footprint ""
		(layer "F.Cu")
		(at 67.39001 -400.76882 180)
		(property "Reference" "C7004"
			(at -5.550662 -2.19583 90)
			(unlocked yes)
			(layer "F.SilkS")
			(effects
				(font
					(size 0.7874 0.5842)
					(thickness 0.1524)
				)
				(justify left)
			)
		)
		(property "Value" ""
			(at 0 0 180)
			(layer "F.Fab")
			(effects
				(font
					(size 1.27 1.27)
				)
			)
		)
		(duplicate_pad_numbers_are_jumpers no)
		(fp_line
			(start 4.53898 2.15011)
			(end -4.53898 2.15011)
			(stroke
				(width 0.1524)
				(type default)
			)
			(layer "F.SilkS")
		)
		(fp_line
			(start 4.53898 -2.15011)
			(end 4.53898 2.15011)
			(stroke
				(width 0.1524)
				(type default)
			)
			(layer "F.SilkS")
		)
		(fp_line
			(start -4.53898 2.15011)
			(end -4.53898 -2.15011)
			(stroke
				(width 0.1524)
				(type default)
			)
			(layer "F.SilkS")
		)
		(fp_line
			(start -4.53898 -2.15011)
			(end 4.53898 -2.15011)
			(stroke
				(width 0.1524)
				(type default)
			)
			(layer "F.SilkS")
		)
		(fp_line
			(start -4.53898 -2.150618)
			(end -4.539742 2.152142)
			(stroke
				(width 0.1524)
				(type default)
			)
			(layer "F.SilkS")
		)
		(fp_line
			(start -4.69138 -2.150618)
			(end -4.692396 2.161032)
			(stroke
				(width 0.1524)
				(type default)
			)
			(layer "F.SilkS")
		)
		(fp_line
			(start -4.83108 2.150364)
			(end -4.447794 2.149348)
			(stroke
				(width 0.1524)
				(type default)
			)
			(layer "F.SilkS")
		)
		(fp_line
			(start -4.84378 -2.150618)
			(end -4.53898 -2.150618)
			(stroke
				(width 0.1524)
				(type default)
			)
			(layer "F.SilkS")
		)
		(fp_line
			(start -4.84378 -2.150618)
			(end -4.842256 2.163064)
			(stroke
				(width 0.1524)
				(type default)
			)
			(layer "F.SilkS")
		)
		(fp_line
			(start 3.64998 2.15011)
			(end -3.64998 2.15011)
			(stroke
				(width 0.1)
				(type default)
			)
			(layer "F.Fab")
		)
		(fp_line
			(start 3.64998 -2.15011)
			(end 3.64998 2.15011)
			(stroke
				(width 0.1)
				(type default)
			)
			(layer "F.Fab")
		)
		(fp_line
			(start -3.64998 2.15011)
			(end -3.64998 -2.15011)
			(stroke
				(width 0.1)
				(type default)
			)
			(layer "F.Fab")
		)
		(fp_line
			(start -3.64998 -2.15011)
			(end 3.64998 -2.15011)
			(stroke
				(width 0.1)
				(type default)
			)
			(layer "F.Fab")
		)
		(fp_text user "-"
			(at 2.763774 2.270252 180)
			(unlocked yes)
			(layer "F.SilkS")
			(effects
				(font
					(size 1.905 1.4224)
					(thickness 0.1524)
				)
				(justify left)
			)
		)
		(fp_text user "+"
			(at -4.553712 2.639822 180)
			(unlocked yes)
			(layer "F.SilkS")
			(effects
				(font
					(size 1.905 1.4224)
					(thickness 0.1524)
				)
				(justify left)
			)
		)
		(fp_text user "-"
			(at 4.313174 -0.094488 180)
			(unlocked yes)
			(layer "F.Fab")
			(effects
				(font
					(size 1.905 1.4224)
					(thickness 0.1524)
				)
				(justify left)
			)
		)
		(fp_text user "+"
			(at -6.214872 -0.337058 180)
			(unlocked yes)
			(layer "F.Fab")
			(effects
				(font
					(size 1.905 1.4224)
					(thickness 0.1524)
				)
				(justify left)
			)
		)
		(pad "1" smd rect
			(at -3.199892 0 180)
			(size 2.413 2.8194)
			(layers "F.Cu" "F.Mask" "F.Paste")
			(net "P0V9_CPU1_RT_2D")
		)
		(pad "2" smd rect
			(at 3.199892 0 180)
			(size 2.413 2.8194)
			(layers "F.Cu" "F.Mask" "F.Paste")
			(net "GND")
		)
	)
	(footprint ""
		(layer "F.Cu")
		(at 257.89128 -49.402746 180)
		(property "Reference" "R3943"
			(at 0 0 180)
			(layer "F.SilkS")
			(hide yes)
			(effects
				(font
					(size 1.27 1.27)
				)
			)
		)
		(property "Value" ""
			(at 0 0 180)
			(layer "F.Fab")
			(effects
				(font
					(size 1.27 1.27)
				)
			)
		)
		(duplicate_pad_numbers_are_jumpers no)
		(fp_line
			(start 0.7874 0.4064)
			(end -0.7874 0.4064)
			(stroke
				(width 0.1524)
				(type default)
			)
			(layer "F.SilkS")
		)
		(fp_line
			(start 0.7874 -0.4064)
			(end 0.7874 0.4064)
			(stroke
				(width 0.1524)
				(type default)
			)
			(layer "F.SilkS")
		)
		(fp_line
			(start -0.7874 0.4064)
			(end -0.7874 -0.4064)
			(stroke
				(width 0.1524)
				(type default)
			)
			(layer "F.SilkS")
		)
		(fp_line
			(start -0.7874 -0.4064)
			(end 0.7874 -0.4064)
			(stroke
				(width 0.1524)
				(type default)
			)
			(layer "F.SilkS")
		)
		(fp_line
			(start 0.67945 0.3048)
			(end 0.120396 0.3048)
			(stroke
				(width 0.1)
				(type default)
			)
			(layer "F.Fab")
		)
		(fp_line
			(start 0.67945 -0.3048)
			(end 0.67945 0.3048)
			(stroke
				(width 0.1)
				(type default)
			)
			(layer "F.Fab")
		)
		(fp_line
			(start 0.12065 -0.2794)
			(end 0.12065 -0.3048)
			(stroke
				(width 0.1)
				(type default)
			)
			(layer "F.Fab")
		)
		(fp_line
			(start 0.12065 -0.3048)
			(end 0.67945 -0.3048)
			(stroke
				(width 0.1)
				(type default)
			)
			(layer "F.Fab")
		)
		(fp_line
			(start 0.120396 0.3048)
			(end 0.120396 0.2794)
			(stroke
				(width 0.1)
				(type default)
			)
			(layer "F.Fab")
		)
		(fp_line
			(start 0.120396 0.2794)
			(end -0.12065 0.2794)
			(stroke
				(width 0.1)
				(type default)
			)
			(layer "F.Fab")
		)
		(fp_line
			(start -0.12065 0.3048)
			(end -0.67945 0.3048)
			(stroke
				(width 0.1)
				(type default)
			)
			(layer "F.Fab")
		)
		(fp_line
			(start -0.12065 0.2794)
			(end -0.12065 0.3048)
			(stroke
				(width 0.1)
				(type default)
			)
			(layer "F.Fab")
		)
		(fp_line
			(start -0.12065 -0.2794)
			(end 0.12065 -0.2794)
			(stroke
				(width 0.1)
				(type default)
			)
			(layer "F.Fab")
		)
		(fp_line
			(start -0.12065 -0.305054)
			(end -0.12065 -0.2794)
			(stroke
				(width 0.1)
				(type default)
			)
			(layer "F.Fab")
		)
		(fp_line
			(start -0.67945 0.3048)
			(end -0.67945 -0.305054)
			(stroke
				(width 0.1)
				(type default)
			)
			(layer "F.Fab")
		)
		(fp_line
			(start -0.67945 -0.305054)
			(end -0.12065 -0.305054)
			(stroke
				(width 0.1)
				(type default)
			)
			(layer "F.Fab")
		)
		(pad "1" smd circle
			(at -0.40005 0 180)
			(size 0 0)
			(layers "F.Cu" "F.Mask" "F.Paste")
			(net "E1S_0_P12V_EN")
		)
		(pad "2" smd circle
			(at 0.40005 0 180)
			(size 0 0)
			(layers "F.Cu" "F.Mask" "F.Paste")
			(net "P12V_E1S_EN_0_R2")
		)
	)
	(footprint ""
		(layer "F.Cu")
		(at 217.881962 -67.324478 180)
		(property "Reference" "PR3965"
			(at 0 0 180)
			(layer "F.SilkS")
			(hide yes)
			(effects
				(font
					(size 1.27 1.27)
				)
			)
		)
		(property "Value" ""
			(at 0 0 180)
			(layer "F.Fab")
			(effects
				(font
					(size 1.27 1.27)
				)
			)
		)
		(duplicate_pad_numbers_are_jumpers no)
		(fp_line
			(start 0.7874 0.4064)
			(end -0.7874 0.4064)
			(stroke
				(width 0.1524)
				(type default)
			)
			(layer "F.SilkS")
		)
		(fp_line
			(start 0.7874 -0.4064)
			(end 0.7874 0.4064)
			(stroke
				(width 0.1524)
				(type default)
			)
			(layer "F.SilkS")
		)
		(fp_line
			(start -0.7874 0.4064)
			(end -0.7874 -0.4064)
			(stroke
				(width 0.1524)
				(type default)
			)
			(layer "F.SilkS")
		)
		(fp_line
			(start -0.7874 -0.4064)
			(end 0.7874 -0.4064)
			(stroke
				(width 0.1524)
				(type default)
			)
			(layer "F.SilkS")
		)
		(fp_line
			(start 0.67945 0.3048)
			(end 0.120396 0.3048)
			(stroke
				(width 0.1)
				(type default)
			)
			(layer "F.Fab")
		)
		(fp_line
			(start 0.67945 -0.3048)
			(end 0.67945 0.3048)
			(stroke
				(width 0.1)
				(type default)
			)
			(layer "F.Fab")
		)
		(fp_line
			(start 0.12065 -0.2794)
			(end 0.12065 -0.3048)
			(stroke
				(width 0.1)
				(type default)
			)
			(layer "F.Fab")
		)
		(fp_line
			(start 0.12065 -0.3048)
			(end 0.67945 -0.3048)
			(stroke
				(width 0.1)
				(type default)
			)
			(layer "F.Fab")
		)
		(fp_line
			(start 0.120396 0.3048)
			(end 0.120396 0.2794)
			(stroke
				(width 0.1)
				(type default)
			)
			(layer "F.Fab")
		)
		(fp_line
			(start 0.120396 0.2794)
			(end -0.12065 0.2794)
			(stroke
				(width 0.1)
				(type default)
			)
			(layer "F.Fab")
		)
		(fp_line
			(start -0.12065 0.3048)
			(end -0.67945 0.3048)
			(stroke
				(width 0.1)
				(type default)
			)
			(layer "F.Fab")
		)
		(fp_line
			(start -0.12065 0.2794)
			(end -0.12065 0.3048)
			(stroke
				(width 0.1)
				(type default)
			)
			(layer "F.Fab")
		)
		(fp_line
			(start -0.12065 -0.2794)
			(end 0.12065 -0.2794)
			(stroke
				(width 0.1)
				(type default)
			)
			(layer "F.Fab")
		)
		(fp_line
			(start -0.12065 -0.305054)
			(end -0.12065 -0.2794)
			(stroke
				(width 0.1)
				(type default)
			)
			(layer "F.Fab")
		)
		(fp_line
			(start -0.67945 0.3048)
			(end -0.67945 -0.305054)
			(stroke
				(width 0.1)
				(type default)
			)
			(layer "F.Fab")
		)
		(fp_line
			(start -0.67945 -0.305054)
			(end -0.12065 -0.305054)
			(stroke
				(width 0.1)
				(type default)
			)
			(layer "F.Fab")
		)
		(pad "1" smd circle
			(at -0.40005 0 180)
			(size 0 0)
			(layers "F.Cu" "F.Mask" "F.Paste")
			(net "P3V3_E1S_OV_0")
		)
		(pad "2" smd circle
			(at 0.40005 0 180)
			(size 0 0)
			(layers "F.Cu" "F.Mask" "F.Paste")
			(net "GND")
		)
	)
	(footprint ""
		(layer "F.Cu")
		(at 136.188958 -62.28207 90)
		(property "Reference" "C194"
			(at 0 0 90)
			(layer "F.SilkS")
			(hide yes)
			(effects
				(font
					(size 1.27 1.27)
				)
			)
		)
		(property "Value" ""
			(at 0 0 90)
			(layer "F.Fab")
			(effects
				(font
					(size 1.27 1.27)
				)
			)
		)
		(duplicate_pad_numbers_are_jumpers no)
		(fp_line
			(start 0.7874 -0.4064)
			(end 0.7874 0.4064)
			(stroke
				(width 0.1524)
				(type default)
			)
			(layer "F.SilkS")
		)
		(fp_line
			(start -0.7874 -0.4064)
			(end 0.7874 -0.4064)
			(stroke
				(width 0.1524)
				(type default)
			)
			(layer "F.SilkS")
		)
		(fp_line
			(start 0.7874 0.4064)
			(end -0.7874 0.4064)
			(stroke
				(width 0.1524)
				(type default)
			)
			(layer "F.SilkS")
		)
		(fp_line
			(start -0.7874 0.4064)
			(end -0.7874 -0.4064)
			(stroke
				(width 0.1524)
				(type default)
			)
			(layer "F.SilkS")
		)
		(fp_line
			(start -0.12065 -0.305054)
			(end -0.12065 -0.2794)
			(stroke
				(width 0.1)
				(type default)
			)
			(layer "F.Fab")
		)
		(fp_line
			(start -0.67945 -0.305054)
			(end -0.12065 -0.305054)
			(stroke
				(width 0.1)
				(type default)
			)
			(layer "F.Fab")
		)
		(fp_line
			(start 0.67945 -0.3048)
			(end 0.67945 0.3048)
			(stroke
				(width 0.1)
				(type default)
			)
			(layer "F.Fab")
		)
		(fp_line
			(start 0.12065 -0.3048)
			(end 0.67945 -0.3048)
			(stroke
				(width 0.1)
				(type default)
			)
			(layer "F.Fab")
		)
		(fp_line
			(start 0.12065 -0.2794)
			(end 0.12065 -0.3048)
			(stroke
				(width 0.1)
				(type default)
			)
			(layer "F.Fab")
		)
		(fp_line
			(start -0.12065 -0.2794)
			(end 0.12065 -0.2794)
			(stroke
				(width 0.1)
				(type default)
			)
			(layer "F.Fab")
		)
		(fp_line
			(start 0.120396 0.2794)
			(end -0.12065 0.2794)
			(stroke
				(width 0.1)
				(type default)
			)
			(layer "F.Fab")
		)
		(fp_line
			(start -0.12065 0.2794)
			(end -0.12065 0.3048)
			(stroke
				(width 0.1)
				(type default)
			)
			(layer "F.Fab")
		)
		(fp_line
			(start 0.67945 0.3048)
			(end 0.120396 0.3048)
			(stroke
				(width 0.1)
				(type default)
			)
			(layer "F.Fab")
		)
		(fp_line
			(start 0.120396 0.3048)
			(end 0.120396 0.2794)
			(stroke
				(width 0.1)
				(type default)
			)
			(layer "F.Fab")
		)
		(fp_line
			(start -0.12065 0.3048)
			(end -0.67945 0.3048)
			(stroke
				(width 0.1)
				(type default)
			)
			(layer "F.Fab")
		)
		(fp_line
			(start -0.67945 0.3048)
			(end -0.67945 -0.305054)
			(stroke
				(width 0.1)
				(type default)
			)
			(layer "F.Fab")
		)
		(pad "1" smd circle
			(at -0.40005 0 90)
			(size 0 0)
			(layers "F.Cu" "F.Mask" "F.Paste")
			(net "P3V3_AUX")
		)
		(pad "2" smd circle
			(at 0.40005 0 90)
			(size 0 0)
			(layers "F.Cu" "F.Mask" "F.Paste")
			(net "GND")
		)
	)
	(footprint ""
		(layer "F.Cu")
		(at 45.605954 -370.57203 -90)
		(property "Reference" "C830"
			(at 0 0 270)
			(layer "F.SilkS")
			(hide yes)
			(effects
				(font
					(size 1.27 1.27)
				)
			)
		)
		(property "Value" ""
			(at 0 0 270)
			(layer "F.Fab")
			(effects
				(font
					(size 1.27 1.27)
				)
			)
		)
		(duplicate_pad_numbers_are_jumpers no)
		(fp_line
			(start -0.299974 0.150114)
			(end -0.299974 -0.150114)
			(stroke
				(width 0.1)
				(type default)
			)
			(layer "F.Fab")
		)
		(fp_line
			(start 0.299974 0.150114)
			(end -0.299974 0.150114)
			(stroke
				(width 0.1)
				(type default)
			)
			(layer "F.Fab")
		)
		(fp_line
			(start -0.299974 -0.150114)
			(end 0.299974 -0.150114)
			(stroke
				(width 0.1)
				(type default)
			)
			(layer "F.Fab")
		)
		(fp_line
			(start 0.299974 -0.150114)
			(end 0.299974 0.150114)
			(stroke
				(width 0.1)
				(type default)
			)
			(layer "F.Fab")
		)
		(pad "1" smd rect
			(at -0.2667 0 270)
			(size 0.3048 0.381)
			(layers "F.Cu" "F.Mask" "F.Paste")
			(net "P5E_CPU1_P0_TX_C_DN<3>")
		)
		(pad "2" smd rect
			(at 0.2667 0 270)
			(size 0.3048 0.381)
			(layers "F.Cu" "F.Mask" "F.Paste")
			(net "P5E_CPU1_P0_TX_DN<3>")
		)
	)
	(footprint ""
		(layer "F.Cu")
		(at 386.211826 -54.1655 180)
		(property "Reference" "R1353"
			(at 0 0 180)
			(layer "F.SilkS")
			(hide yes)
			(effects
				(font
					(size 1.27 1.27)
				)
			)
		)
		(property "Value" ""
			(at 0 0 180)
			(layer "F.Fab")
			(effects
				(font
					(size 1.27 1.27)
				)
			)
		)
		(duplicate_pad_numbers_are_jumpers no)
		(fp_line
			(start 0.7874 0.4064)
			(end -0.7874 0.4064)
			(stroke
				(width 0.1524)
				(type default)
			)
			(layer "F.SilkS")
		)
		(fp_line
			(start 0.7874 -0.4064)
			(end 0.7874 0.4064)
			(stroke
				(width 0.1524)
				(type default)
			)
			(layer "F.SilkS")
		)
		(fp_line
			(start -0.7874 0.4064)
			(end -0.7874 -0.4064)
			(stroke
				(width 0.1524)
				(type default)
			)
			(layer "F.SilkS")
		)
		(fp_line
			(start -0.7874 -0.4064)
			(end 0.7874 -0.4064)
			(stroke
				(width 0.1524)
				(type default)
			)
			(layer "F.SilkS")
		)
		(fp_line
			(start 0.67945 0.3048)
			(end 0.120396 0.3048)
			(stroke
				(width 0.1)
				(type default)
			)
			(layer "F.Fab")
		)
		(fp_line
			(start 0.67945 -0.3048)
			(end 0.67945 0.3048)
			(stroke
				(width 0.1)
				(type default)
			)
			(layer "F.Fab")
		)
		(fp_line
			(start 0.12065 -0.2794)
			(end 0.12065 -0.3048)
			(stroke
				(width 0.1)
				(type default)
			)
			(layer "F.Fab")
		)
		(fp_line
			(start 0.12065 -0.3048)
			(end 0.67945 -0.3048)
			(stroke
				(width 0.1)
				(type default)
			)
			(layer "F.Fab")
		)
		(fp_line
			(start 0.120396 0.3048)
			(end 0.120396 0.2794)
			(stroke
				(width 0.1)
				(type default)
			)
			(layer "F.Fab")
		)
		(fp_line
			(start 0.120396 0.2794)
			(end -0.12065 0.2794)
			(stroke
				(width 0.1)
				(type default)
			)
			(layer "F.Fab")
		)
		(fp_line
			(start -0.12065 0.3048)
			(end -0.67945 0.3048)
			(stroke
				(width 0.1)
				(type default)
			)
			(layer "F.Fab")
		)
		(fp_line
			(start -0.12065 0.2794)
			(end -0.12065 0.3048)
			(stroke
				(width 0.1)
				(type default)
			)
			(layer "F.Fab")
		)
		(fp_line
			(start -0.12065 -0.2794)
			(end 0.12065 -0.2794)
			(stroke
				(width 0.1)
				(type default)
			)
			(layer "F.Fab")
		)
		(fp_line
			(start -0.12065 -0.305054)
			(end -0.12065 -0.2794)
			(stroke
				(width 0.1)
				(type default)
			)
			(layer "F.Fab")
		)
		(fp_line
			(start -0.67945 0.3048)
			(end -0.67945 -0.305054)
			(stroke
				(width 0.1)
				(type default)
			)
			(layer "F.Fab")
		)
		(fp_line
			(start -0.67945 -0.305054)
			(end -0.12065 -0.305054)
			(stroke
				(width 0.1)
				(type default)
			)
			(layer "F.Fab")
		)
		(pad "1" smd circle
			(at -0.40005 0 180)
			(size 0 0)
			(layers "F.Cu" "F.Mask" "F.Paste")
			(net "HDT_HDR_R_TMS")
		)
		(pad "2" smd circle
			(at 0.40005 0 180)
			(size 0 0)
			(layers "F.Cu" "F.Mask" "F.Paste")
			(net "HDT_HDR_TMS")
		)
	)
)
